# SCM (Grand Teton) — schematic netlist excerpt (pin names and nets, part order shuffled) for the footprints in the layout excerpt that follows; sources: Cadence DE-HDL packaged netlist, KiCad conversion of 12092022_DA0F0TMDCD0_F0T_Management_Board_D_brd_V3_OCP.brd

D5  Q_LED  IC  pkg SMLF  page 47 : A = LED_POSTCODE_5_R ; C = GND
R315  Q_RES  0 5% EMPTY  pkg 0402LF  page 22 : A = RST_BMC_SRST_BUF_R_N ; B = RST_BMC_SRST_BUF_R1_N

(kicad_pcb
	(version 20260206)
	(generator "pcbnew")
	(generator_version "10.0")
	(general
		(thickness 1.6)
		(legacy_teardrops no)
	)
	(paper "A4")
	(title_block
		(title "12092022_DA0F0TMDCD0_F0T_Management_Board_D_brd_V3_OCP.brd")
		(comment 1 "Grand Teton / footprints 584-585 of 1440")
	)
	(layers
		(0 "F.Cu" signal "TOP")
		(4 "In1.Cu" signal "GND")
		(6 "In2.Cu" signal "IN1")
		(8 "In3.Cu" signal "GND1")
		(10 "In4.Cu" signal "IN2")
		(12 "In5.Cu" signal "VCC")
		(14 "In6.Cu" signal "VCC1")
		(16 "In7.Cu" signal "IN3")
		(18 "In8.Cu" signal "GND2")
		(20 "In9.Cu" signal "IN4")
		(22 "In10.Cu" signal "GND3")
		(2 "B.Cu" signal "BOTTOM")
		(9 "F.Adhes" user "F.Adhesive")
		(11 "B.Adhes" user "B.Adhesive")
		(13 "F.Paste" user "Package Geometry/Pastemask Top")
		(15 "B.Paste" user "Package Geometry/Pastemask Bottom")
		(5 "F.SilkS" user "Ref Des/Silkscreen Top")
		(7 "B.SilkS" user "Ref Des/Silkscreen Bottom")
		(1 "F.Mask" user "Board Geometry/Soldermask Top")
		(3 "B.Mask" user "Board Geometry/Soldermask Bottom")
		(17 "Dwgs.User" user "User.Drawings")
		(19 "Cmts.User" user "User.Comments")
		(21 "Eco1.User" user "User.Eco1")
		(23 "Eco2.User" user "User.Eco2")
		(25 "Edge.Cuts" user "Board Geometry/Outline")
		(27 "Margin" user)
		(31 "F.CrtYd" user "Package Geometry/Place Bound Top")
		(29 "B.CrtYd" user "Package Geometry/Place Bound Bottom")
		(35 "F.Fab" user "Ref Des/Assembly Top")
		(33 "B.Fab" user "Ref Des/Assembly Bottom")
	)
	(footprint ""
		(layer "F.Cu")
		(at 77.281786 -31.307786 90)
		(property "Reference" "D5"
			(at -3.621786 7.580884 90)
			(unlocked yes)
			(layer "F.SilkS")
			(effects
				(font
					(size 0.7874 0.5842)
					(thickness 0.1524)
				)
				(justify left)
			)
		)
		(property "Value" ""
			(at 0 0 90)
			(layer "F.Fab")
			(effects
				(font
					(size 1.27 1.27)
				)
			)
		)
		(duplicate_pad_numbers_are_jumpers no)
		(fp_line
			(start 1.778 -0.5588)
			(end 1.3208 -0.5588)
			(stroke
				(width 0.1524)
				(type default)
			)
			(layer "F.SilkS")
		)
		(fp_line
			(start 1.778 -0.5588)
			(end 1.778 0.5588)
			(stroke
				(width 0.1524)
				(type default)
			)
			(layer "F.SilkS")
		)
		(fp_line
			(start 1.4732 -0.5588)
			(end 1.4732 0.5588)
			(stroke
				(width 0.1524)
				(type default)
			)
			(layer "F.SilkS")
		)
		(fp_line
			(start 1.3208 -0.5588)
			(end 1.3208 0.5588)
			(stroke
				(width 0.1524)
				(type default)
			)
			(layer "F.SilkS")
		)
		(fp_line
			(start -1.3208 -0.5588)
			(end 1.3208 -0.5588)
			(stroke
				(width 0.1524)
				(type default)
			)
			(layer "F.SilkS")
		)
		(fp_line
			(start 1.778 0.5588)
			(end 1.3208 0.5588)
			(stroke
				(width 0.1524)
				(type default)
			)
			(layer "F.SilkS")
		)
		(fp_line
			(start 1.6256 0.5588)
			(end 1.6256 -0.5588)
			(stroke
				(width 0.1524)
				(type default)
			)
			(layer "F.SilkS")
		)
		(fp_line
			(start 1.3208 0.5588)
			(end -1.3208 0.5588)
			(stroke
				(width 0.1524)
				(type default)
			)
			(layer "F.SilkS")
		)
		(fp_line
			(start -1.3208 0.5588)
			(end -1.3208 -0.5588)
			(stroke
				(width 0.1524)
				(type default)
			)
			(layer "F.SilkS")
		)
		(fp_line
			(start 0.8001 -0.40005)
			(end 0.8001 0.40005)
			(stroke
				(width 0.1)
				(type default)
			)
			(layer "F.Fab")
		)
		(fp_line
			(start -0.8001 -0.40005)
			(end 0.8001 -0.40005)
			(stroke
				(width 0.1)
				(type default)
			)
			(layer "F.Fab")
		)
		(fp_line
			(start 0.8001 0.40005)
			(end -0.8001 0.40005)
			(stroke
				(width 0.1)
				(type default)
			)
			(layer "F.Fab")
		)
		(fp_line
			(start -0.8001 0.40005)
			(end -0.8001 -0.40005)
			(stroke
				(width 0.1)
				(type default)
			)
			(layer "F.Fab")
		)
		(fp_text user "-"
			(at 1.661414 -1.024636 90)
			(unlocked yes)
			(layer "F.SilkS")
			(effects
				(font
					(size 1.905 1.4224)
					(thickness 0.1524)
				)
				(justify left)
			)
		)
		(fp_text user "+"
			(at -0.853186 -0.605536 270)
			(unlocked yes)
			(layer "F.SilkS")
			(effects
				(font
					(size 1.905 1.4224)
					(thickness 0.1524)
				)
				(justify left)
			)
		)
		(fp_text user "-"
			(at 1.6256 -0.22225 90)
			(unlocked yes)
			(layer "F.Fab")
			(effects
				(font
					(size 1.905 1.4224)
					(thickness 0.1524)
				)
				(justify left)
			)
		)
		(fp_text user "+"
			(at -2.5654 -0.22225 90)
			(unlocked yes)
			(layer "F.Fab")
			(effects
				(font
					(size 1.905 1.4224)
					(thickness 0.1524)
				)
				(justify left)
			)
		)
		(pad "A" smd rect
			(at -0.750062 0 90)
			(size 0.8128 0.8128)
			(layers "F.Cu" "F.Mask" "F.Paste")
			(net "LED_POSTCODE_5_R")
		)
		(pad "C" smd rect
			(at 0.750062 0 90)
			(size 0.8128 0.8128)
			(layers "F.Cu" "F.Mask" "F.Paste")
			(net "GND")
		)
	)
	(footprint ""
		(layer "F.Cu")
		(at 10.922 -105.5878)
		(property "Reference" "R315"
			(at 0 0 0)
			(layer "F.SilkS")
			(hide yes)
			(effects
				(font
					(size 1.27 1.27)
				)
			)
		)
		(property "Value" ""
			(at 0 0 0)
			(layer "F.Fab")
			(effects
				(font
					(size 1.27 1.27)
				)
			)
		)
		(duplicate_pad_numbers_are_jumpers no)
		(fp_line
			(start -0.7874 -0.4064)
			(end 0.7874 -0.4064)
			(stroke
				(width 0.1524)
				(type default)
			)
			(layer "F.SilkS")
		)
		(fp_line
			(start -0.7874 0.4064)
			(end -0.7874 -0.4064)
			(stroke
				(width 0.1524)
				(type default)
			)
			(layer "F.SilkS")
		)
		(fp_line
			(start 0.7874 -0.4064)
			(end 0.7874 0.4064)
			(stroke
				(width 0.1524)
				(type default)
			)
			(layer "F.SilkS")
		)
		(fp_line
			(start 0.7874 0.4064)
			(end -0.7874 0.4064)
			(stroke
				(width 0.1524)
				(type default)
			)
			(layer "F.SilkS")
		)
		(fp_line
			(start -0.67945 -0.305054)
			(end -0.12065 -0.305054)
			(stroke
				(width 0.1)
				(type default)
			)
			(layer "F.Fab")
		)
		(fp_line
			(start -0.67945 0.3048)
			(end -0.67945 -0.305054)
			(stroke
				(width 0.1)
				(type default)
			)
			(layer "F.Fab")
		)
		(fp_line
			(start -0.12065 -0.305054)
			(end -0.12065 -0.2794)
			(stroke
				(width 0.1)
				(type default)
			)
			(layer "F.Fab")
		)
		(fp_line
			(start -0.12065 -0.2794)
			(end 0.12065 -0.2794)
			(stroke
				(width 0.1)
				(type default)
			)
			(layer "F.Fab")
		)
		(fp_line
			(start -0.12065 0.2794)
			(end -0.12065 0.3048)
			(stroke
				(width 0.1)
				(type default)
			)
			(layer "F.Fab")
		)
		(fp_line
			(start -0.12065 0.3048)
			(end -0.67945 0.3048)
			(stroke
				(width 0.1)
				(type default)
			)
			(layer "F.Fab")
		)
		(fp_line
			(start 0.120396 0.2794)
			(end -0.12065 0.2794)
			(stroke
				(width 0.1)
				(type default)
			)
			(layer "F.Fab")
		)
		(fp_line
			(start 0.120396 0.3048)
			(end 0.120396 0.2794)
			(stroke
				(width 0.1)
				(type default)
			)
			(layer "F.Fab")
		)
		(fp_line
			(start 0.12065 -0.3048)
			(end 0.67945 -0.3048)
			(stroke
				(width 0.1)
				(type default)
			)
			(layer "F.Fab")
		)
		(fp_line
			(start 0.12065 -0.2794)
			(end 0.12065 -0.3048)
			(stroke
				(width 0.1)
				(type default)
			)
			(layer "F.Fab")
		)
		(fp_line
			(start 0.67945 -0.3048)
			(end 0.67945 0.3048)
			(stroke
				(width 0.1)
				(type default)
			)
			(layer "F.Fab")
		)
		(fp_line
			(start 0.67945 0.3048)
			(end 0.120396 0.3048)
			(stroke
				(width 0.1)
				(type default)
			)
			(layer "F.Fab")
		)
		(pad "1" smd circle
			(at -0.40005 0)
			(size 0 0)
			(layers "F.Cu" "F.Mask" "F.Paste")
			(net "RST_BMC_SRST_BUF_R_N")
		)
		(pad "2" smd circle
			(at 0.40005 0)
			(size 0 0)
			(layers "F.Cu" "F.Mask" "F.Paste")
			(net "RST_BMC_SRST_BUF_R1_N")
		)
	)
)
